(kicad_pcb
	(version 20260206)
	(generator "pcbnew")
	(generator_version "10.0")
	(general
		(thickness 1.6)
		(legacy_teardrops no)
	)
	(paper "A4")
	(title_block
		(title "timecard-production-celestica-r4006 — R4006-B0001-02_R01.brd")
		(comment 1 "Time Appliance Project (Time Card) / footprints 372-377 of 1113")
	)
	(layers
		(0 "F.Cu" signal "TOP")
		(4 "In1.Cu" signal "L02_GND1")
		(6 "In2.Cu" signal "L03_SIG1")
		(8 "In3.Cu" signal "L04_GND2")
		(10 "In4.Cu" signal "L05_VCC1")
		(12 "In5.Cu" signal "L06_VCC2")
		(14 "In6.Cu" signal "L07_GND3")
		(16 "In7.Cu" signal "L08_SIG2")
		(18 "In8.Cu" signal "L09_GND4")
		(2 "B.Cu" signal "BOTTOM")
		(9 "F.Adhes" user "F.Adhesive")
		(11 "B.Adhes" user "B.Adhesive")
		(13 "F.Paste" user "Package Geometry/Pastemask Top")
		(15 "B.Paste" user "Package Geometry/Pastemask Bottom")
		(5 "F.SilkS" user "Ref Des/Silkscreen Top")
		(7 "B.SilkS" user "Ref Des/Silkscreen Bottom")
		(1 "F.Mask" user "Board Geometry/Soldermask Top")
		(3 "B.Mask" user "Board Geometry/Soldermask Bottom")
		(17 "Dwgs.User" user "User.Drawings")
		(19 "Cmts.User" user "User.Comments")
		(21 "Eco1.User" user "User.Eco1")
		(23 "Eco2.User" user "User.Eco2")
		(25 "Edge.Cuts" user "Board Geometry/Outline")
		(27 "Margin" user)
		(31 "F.CrtYd" user "Package Geometry/Place Bound Top")
		(29 "B.CrtYd" user "Package Geometry/Place Bound Bottom")
		(35 "F.Fab" user "Ref Des/Assembly Top")
		(33 "B.Fab" user "Ref Des/Assembly Bottom")
	)
	(footprint ""
		(layer "F.Cu")
		(at 80.772 -57.2516)
		(property "Reference" "R79"
			(at -10.668 -19.39163 0)
			(unlocked yes)
			(layer "F.SilkS")
			(effects
				(font
					(size 0.7874 0.5842)
					(thickness 0.1524)
				)
			)
		)
		(property "Value" "VAL*"
			(at 0.02032 2.13233 0)
			(unlocked yes)
			(layer "F.Fab")
			(hide yes)
			(effects
				(font
					(size 0.7874 0.5842)
					(thickness 0.1524)
				)
			)
		)
		(property "Tolerance" "TOL*"
			(at 0.044704 3.05435 0)
			(unlocked yes)
			(layer "Cmts.User")
			(hide yes)
			(effects
				(font
					(size 0.7874 0.5842)
					(thickness 0.1524)
				)
			)
		)
		(property "User Part Number" "PARTNUM*"
			(at 0.02032 4.024884 0)
			(unlocked yes)
			(layer "Cmts.User")
			(hide yes)
			(effects
				(font
					(size 0.7874 0.5842)
					(thickness 0.1524)
				)
			)
		)
		(property "Device Type" "RESISTOR-G155-133R0-01,33OHM,1%"
			(at 0.008382 1.210564 0)
			(unlocked yes)
			(layer "F.Fab")
			(hide yes)
			(effects
				(font
					(size 0.7874 0.5842)
					(thickness 0.1524)
				)
			)
		)
		(duplicate_pad_numbers_are_jumpers no)
		(fp_line
			(start -1.143 -0.5588)
			(end -1.143 0.5588)
			(stroke
				(width 0.1)
				(type default)
			)
			(layer "F.SilkS")
		)
		(fp_line
			(start -1.143 0.5588)
			(end 1.143 0.5588)
			(stroke
				(width 0.1)
				(type default)
			)
			(layer "F.SilkS")
		)
		(fp_line
			(start 1.143 -0.5588)
			(end -1.143 -0.5588)
			(stroke
				(width 0.1)
				(type default)
			)
			(layer "F.SilkS")
		)
		(fp_line
			(start 1.143 0.5588)
			(end 1.143 -0.5588)
			(stroke
				(width 0.1)
				(type default)
			)
			(layer "F.SilkS")
		)
		(fp_rect
			(start -1.143 0.5588)
			(end 1.143 -0.5588)
			(stroke
				(width 0)
				(type default)
			)
			(fill no)
			(layer "F.CrtYd")
		)
		(fp_line
			(start -0.508 -0.3048)
			(end -0.508 0.3048)
			(stroke
				(width 0.1)
				(type default)
			)
			(layer "F.Fab")
		)
		(fp_line
			(start -0.508 0.3048)
			(end 0.508 0.3048)
			(stroke
				(width 0.1)
				(type default)
			)
			(layer "F.Fab")
		)
		(fp_line
			(start 0.508 -0.3048)
			(end -0.508 -0.3048)
			(stroke
				(width 0.1)
				(type default)
			)
			(layer "F.Fab")
		)
		(fp_line
			(start 0.508 0.3048)
			(end 0.508 -0.3048)
			(stroke
				(width 0.1)
				(type default)
			)
			(layer "F.Fab")
		)
		(pad "1" smd rect
			(at -0.5334 0)
			(size 0.7112 0.6096)
			(layers "F.Cu" "F.Mask" "F.Paste")
			(net "FPGA_IN_BNO080_INT_N")
		)
		(pad "2" smd rect
			(at 0.5334 0)
			(size 0.7112 0.6096)
			(layers "F.Cu" "F.Mask" "F.Paste")
			(net "R_BNO080_INT_N")
		)
		(zone
			(layer "F.Cu")
			(hatch none 0.5)
			(connect_pads
				(clearance 0)
			)
			(min_thickness 0.25)
			(keepout
				(tracks allowed)
				(vias not_allowed)
				(pads allowed)
				(copperpour not_allowed)
				(footprints allowed)
			)
			(placement
				(enabled no)
				(sheetname "")
			)
			(fill
				(thermal_gap 0.5)
				(thermal_bridge_width 0.5)
				(island_removal_mode 0)
			)
			(polygon
				(pts
					(xy 80.6958 -56.9468) (xy 80.8482 -56.9468) (xy 80.8482 -57.5564) (xy 80.6958 -57.5564)
				)
			)
		)
	)
	(footprint ""
		(layer "F.Cu")
		(at 15.748 -50.673)
		(property "Reference" "TP33"
			(at 1.18237 3.3782 90)
			(unlocked yes)
			(layer "F.SilkS")
			(effects
				(font
					(size 0.7874 0.5842)
					(thickness 0.1524)
				)
				(justify left)
			)
		)
		(property "Value" ""
			(at 0 0 0)
			(layer "F.Fab")
			(effects
				(font
					(size 1.27 1.27)
				)
			)
		)
		(property "Device Type" "TP_PIONT-TP010CT020B030_PTH-TPA"
			(at -1.341882 0.996696 0)
			(unlocked yes)
			(layer "F.Fab")
			(hide yes)
			(effects
				(font
					(size 0.7874 0.5842)
					(thickness 0.000001)
				)
				(justify left)
			)
		)
		(duplicate_pad_numbers_are_jumpers no)
		(fp_poly
			(pts
				(arc
					(start 0.889 0)
					(mid -0.889 0)
					(end 0.889 0)
				)
			)
			(stroke
				(width 0)
				(type default)
			)
			(fill no)
			(layer "B.CrtYd")
		)
		(fp_poly
			(pts
				(arc
					(start 0.889 0)
					(mid -0.889 0)
					(end 0.889 0)
				)
			)
			(stroke
				(width 0)
				(type default)
			)
			(fill no)
			(layer "F.CrtYd")
		)
		(pad "1" thru_hole circle
			(at 0 0)
			(size 0.508 0.508)
			(drill 0.254)
			(layers "*.Cu" "*.Mask")
			(remove_unused_layers no)
			(net "SMA2_SIG_OUT_BF_EN_N")
			(clearance 0.1016)
			(padstack
				(mode front_inner_back)
				(layer "Inner"
					(shape circle)
					(size 0.508 0.508)
					(clearance 0.1016)
				)
				(layer "B.Cu"
					(shape circle)
					(size 0.762 0.762)
					(clearance -0.0254)
				)
			)
		)
	)
	(footprint ""
		(layer "F.Cu")
		(at 52.01158 -15.5194 -90)
		(property "Reference" "R25"
			(at -3.0226 -0.22479 90)
			(unlocked yes)
			(layer "F.SilkS")
			(effects
				(font
					(size 0.7874 0.5842)
					(thickness 0.1524)
				)
			)
		)
		(property "Value" "VAL*"
			(at 0.02032 2.13233 270)
			(unlocked yes)
			(layer "F.Fab")
			(hide yes)
			(effects
				(font
					(size 0.7874 0.5842)
					(thickness 0.1524)
				)
			)
		)
		(property "Tolerance" "TOL*"
			(at 0.044704 3.05435 270)
			(unlocked yes)
			(layer "Cmts.User")
			(hide yes)
			(effects
				(font
					(size 0.7874 0.5842)
					(thickness 0.1524)
				)
			)
		)
		(property "User Part Number" "PARTNUM*"
			(at 0.02032 4.024884 270)
			(unlocked yes)
			(layer "Cmts.User")
			(hide yes)
			(effects
				(font
					(size 0.7874 0.5842)
					(thickness 0.1524)
				)
			)
		)
		(property "Device Type" "RESISTOR-G155-14701-01,4.7KOHMA"
			(at 0.008382 1.210564 270)
			(unlocked yes)
			(layer "F.Fab")
			(hide yes)
			(effects
				(font
					(size 0.7874 0.5842)
					(thickness 0.1524)
				)
			)
		)
		(duplicate_pad_numbers_are_jumpers no)
		(fp_line
			(start -1.143 0.5588)
			(end 1.143 0.5588)
			(stroke
				(width 0.1)
				(type default)
			)
			(layer "F.SilkS")
		)
		(fp_line
			(start 1.143 0.5588)
			(end 1.143 -0.5588)
			(stroke
				(width 0.1)
				(type default)
			)
			(layer "F.SilkS")
		)
		(fp_line
			(start -1.143 -0.5588)
			(end -1.143 0.5588)
			(stroke
				(width 0.1)
				(type default)
			)
			(layer "F.SilkS")
		)
		(fp_line
			(start 1.143 -0.5588)
			(end -1.143 -0.5588)
			(stroke
				(width 0.1)
				(type default)
			)
			(layer "F.SilkS")
		)
		(fp_rect
			(start 1.143 0.5588)
			(end -1.143 -0.5588)
			(stroke
				(width 0)
				(type default)
			)
			(fill no)
			(layer "F.CrtYd")
		)
		(fp_line
			(start -0.508 0.3048)
			(end 0.508 0.3048)
			(stroke
				(width 0.1)
				(type default)
			)
			(layer "F.Fab")
		)
		(fp_line
			(start 0.508 0.3048)
			(end 0.508 -0.3048)
			(stroke
				(width 0.1)
				(type default)
			)
			(layer "F.Fab")
		)
		(fp_line
			(start -0.508 -0.3048)
			(end -0.508 0.3048)
			(stroke
				(width 0.1)
				(type default)
			)
			(layer "F.Fab")
		)
		(fp_line
			(start 0.508 -0.3048)
			(end -0.508 -0.3048)
			(stroke
				(width 0.1)
				(type default)
			)
			(layer "F.Fab")
		)
		(pad "1" smd rect
			(at -0.5334 0 270)
			(size 0.7112 0.6096)
			(layers "F.Cu" "F.Mask" "F.Paste")
			(net "XP3R3V_FPGA")
		)
		(pad "2" smd rect
			(at 0.5334 0 270)
			(size 0.7112 0.6096)
			(layers "F.Cu" "F.Mask" "F.Paste")
			(net "UNNAMED_3_G2201019801_I100_EN")
		)
		(zone
			(layer "F.Cu")
			(hatch none 0.5)
			(connect_pads
				(clearance 0)
			)
			(min_thickness 0.25)
			(keepout
				(tracks allowed)
				(vias not_allowed)
				(pads allowed)
				(copperpour not_allowed)
				(footprints allowed)
			)
			(placement
				(enabled no)
				(sheetname "")
			)
			(fill
				(thermal_gap 0.5)
				(thermal_bridge_width 0.5)
				(island_removal_mode 0)
			)
			(polygon
				(pts
					(xy 51.70678 -15.4432) (xy 52.31638 -15.4432) (xy 52.31638 -15.5956) (xy 51.70678 -15.5956)
				)
			)
		)
	)
	(footprint ""
		(layer "F.Cu")
		(at 130.048 -98.552 90)
		(property "Reference" "L15"
			(at 1.5875 0.67437 90)
			(unlocked yes)
			(layer "F.SilkS")
			(effects
				(font
					(size 0.7874 0.5842)
					(thickness 0.1524)
				)
				(justify left)
			)
		)
		(property "Value" "VAL*"
			(at -0.9398 3.70967 90)
			(unlocked yes)
			(layer "F.Fab")
			(hide yes)
			(effects
				(font
					(size 0.7874 0.5842)
					(thickness 0.1524)
				)
				(justify left)
			)
		)
		(property "Tolerance" "TOL*"
			(at -0.9906 5.00507 90)
			(unlocked yes)
			(layer "Cmts.User")
			(hide yes)
			(effects
				(font
					(size 0.7874 0.5842)
					(thickness 0.1524)
				)
				(justify left)
			)
		)
		(property "User Part Number" "PARTNUM*"
			(at -2.54 2.46507 90)
			(unlocked yes)
			(layer "Cmts.User")
			(hide yes)
			(effects
				(font
					(size 0.7874 0.5842)
					(thickness 0.1524)
				)
				(justify left)
			)
		)
		(property "Device Type" "FERRITEBEAD-G191-10100-01,120OA"
			(at -0.9906 1.22047 90)
			(unlocked yes)
			(layer "F.Fab")
			(hide yes)
			(effects
				(font
					(size 0.7874 0.5842)
					(thickness 0.1524)
				)
				(justify left)
			)
		)
		(duplicate_pad_numbers_are_jumpers no)
		(fp_line
			(start 1.3208 -0.7112)
			(end 1.3208 0.7112)
			(stroke
				(width 0.1)
				(type default)
			)
			(layer "F.SilkS")
		)
		(fp_line
			(start -1.3208 -0.7112)
			(end 1.3208 -0.7112)
			(stroke
				(width 0.1)
				(type default)
			)
			(layer "F.SilkS")
		)
		(fp_line
			(start 1.3208 0.7112)
			(end -1.3208 0.7112)
			(stroke
				(width 0.1)
				(type default)
			)
			(layer "F.SilkS")
		)
		(fp_line
			(start -1.3208 0.7112)
			(end -1.3208 -0.7112)
			(stroke
				(width 0.1)
				(type default)
			)
			(layer "F.SilkS")
		)
		(fp_rect
			(start -1.3208 0.7112)
			(end 1.3208 -0.7112)
			(stroke
				(width 0)
				(type default)
			)
			(fill no)
			(layer "F.CrtYd")
		)
		(fp_line
			(start 0.8128 -0.4572)
			(end 0.8128 0.4572)
			(stroke
				(width 0.1)
				(type default)
			)
			(layer "F.Fab")
		)
		(fp_line
			(start -0.8128 -0.4572)
			(end 0.8128 -0.4572)
			(stroke
				(width 0.1)
				(type default)
			)
			(layer "F.Fab")
		)
		(fp_line
			(start 0.8128 0.4572)
			(end -0.8128 0.4572)
			(stroke
				(width 0.1)
				(type default)
			)
			(layer "F.Fab")
		)
		(fp_line
			(start -0.8128 0.4572)
			(end -0.8128 -0.4572)
			(stroke
				(width 0.1)
				(type default)
			)
			(layer "F.Fab")
		)
		(pad "1" smd rect
			(at -0.6858 0 90)
			(size 0.762 0.8636)
			(layers "F.Cu" "F.Mask" "F.Paste")
			(net "XP5R0V")
		)
		(pad "2" smd rect
			(at 0.6858 0 90)
			(size 0.762 0.8636)
			(layers "F.Cu" "F.Mask" "F.Paste")
			(net "XP5R0V_VCC_ANT")
		)
		(zone
			(layer "F.Cu")
			(hatch none 0.5)
			(connect_pads
				(clearance 0)
			)
			(min_thickness 0.25)
			(keepout
				(tracks allowed)
				(vias not_allowed)
				(pads allowed)
				(copperpour not_allowed)
				(footprints allowed)
			)
			(placement
				(enabled no)
				(sheetname "")
			)
			(fill
				(thermal_gap 0.5)
				(thermal_bridge_width 0.5)
				(island_removal_mode 0)
			)
			(polygon
				(pts
					(xy 130.5052 -98.3996) (xy 130.5052 -98.7044) (xy 129.5908 -98.7044) (xy 129.5908 -98.3996)
				)
			)
		)
		(zone
			(layer "F.Cu")
			(hatch none 0.5)
			(connect_pads
				(clearance 0)
			)
			(min_thickness 0.25)
			(keepout
				(tracks not_allowed)
				(vias allowed)
				(pads allowed)
				(copperpour not_allowed)
				(footprints allowed)
			)
			(placement
				(enabled no)
				(sheetname "")
			)
			(fill
				(thermal_gap 0.5)
				(thermal_bridge_width 0.5)
				(island_removal_mode 0)
			)
			(polygon
				(pts
					(xy 130.5052 -98.3996) (xy 130.5052 -98.7044) (xy 129.5908 -98.7044) (xy 129.5908 -98.3996)
				)
			)
		)
	)
	(footprint ""
		(layer "F.Cu")
		(at 24.003 -75.946)
		(property "Reference" "TP9"
			(at 0 0 0)
			(layer "F.SilkS")
			(hide yes)
			(effects
				(font
					(size 1.27 1.27)
				)
			)
		)
		(property "Value" ""
			(at 0 0 0)
			(layer "F.Fab")
			(effects
				(font
					(size 1.27 1.27)
				)
			)
		)
		(property "Device Type" "TP_PIONT-TP010CT020B030_PTH-TPA"
			(at -1.341882 0.996696 0)
			(unlocked yes)
			(layer "F.Fab")
			(hide yes)
			(effects
				(font
					(size 0.7874 0.5842)
					(thickness 0.1524)
				)
				(justify left)
			)
		)
		(duplicate_pad_numbers_are_jumpers no)
		(fp_poly
			(pts
				(arc
					(start 0.889 0)
					(mid -0.889 0)
					(end 0.889 0)
				)
			)
			(stroke
				(width 0)
				(type default)
			)
			(fill no)
			(layer "B.CrtYd")
		)
		(fp_poly
			(pts
				(arc
					(start 0.889 0)
					(mid -0.889 0)
					(end 0.889 0)
				)
			)
			(stroke
				(width 0)
				(type default)
			)
			(fill no)
			(layer "F.CrtYd")
		)
		(pad "1" thru_hole circle
			(at 0 0)
			(size 0.508 0.508)
			(drill 0.254)
			(layers "*.Cu" "*.Mask")
			(remove_unused_layers no)
			(net "UNNAMED_524_FT4232HLREELQFP64_4")
			(clearance 0.1016)
			(padstack
				(mode front_inner_back)
				(layer "Inner"
					(shape circle)
					(size 0.508 0.508)
					(clearance 0.1016)
				)
				(layer "B.Cu"
					(shape circle)
					(size 0.762 0.762)
					(clearance -0.0254)
				)
			)
		)
	)
	(footprint ""
		(layer "F.Cu")
		(at 126.492 -33.909 180)
		(property "Reference" "R194"
			(at -2.921 -1.43637 0)
			(unlocked yes)
			(layer "F.SilkS")
			(effects
				(font
					(size 0.7874 0.5842)
					(thickness 0.1524)
				)
			)
		)
		(property "Value" "VAL*"
			(at 0.02032 2.13233 180)
			(unlocked yes)
			(layer "F.Fab")
			(hide yes)
			(effects
				(font
					(size 0.7874 0.5842)
					(thickness 0.1524)
				)
			)
		)
		(property "Tolerance" "TOL*"
			(at 0.044704 3.05435 180)
			(unlocked yes)
			(layer "Cmts.User")
			(hide yes)
			(effects
				(font
					(size 0.7874 0.5842)
					(thickness 0.1524)
				)
			)
		)
		(property "User Part Number" "PARTNUM*"
			(at 0.02032 4.024884 180)
			(unlocked yes)
			(layer "Cmts.User")
			(hide yes)
			(effects
				(font
					(size 0.7874 0.5842)
					(thickness 0.1524)
				)
			)
		)
		(property "Device Type" "RESISTOR-G155-14701-01,4.7KOHMA"
			(at 0.008382 1.210564 180)
			(unlocked yes)
			(layer "F.Fab")
			(hide yes)
			(effects
				(font
					(size 0.7874 0.5842)
					(thickness 0.1524)
				)
			)
		)
		(duplicate_pad_numbers_are_jumpers no)
		(fp_line
			(start 1.143 0.5588)
			(end 1.143 -0.5588)
			(stroke
				(width 0.1)
				(type default)
			)
			(layer "F.SilkS")
		)
		(fp_line
			(start 1.143 -0.5588)
			(end -1.143 -0.5588)
			(stroke
				(width 0.1)
				(type default)
			)
			(layer "F.SilkS")
		)
		(fp_line
			(start -1.143 0.5588)
			(end 1.143 0.5588)
			(stroke
				(width 0.1)
				(type default)
			)
			(layer "F.SilkS")
		)
		(fp_line
			(start -1.143 -0.5588)
			(end -1.143 0.5588)
			(stroke
				(width 0.1)
				(type default)
			)
			(layer "F.SilkS")
		)
		(fp_rect
			(start 1.143 0.5588)
			(end -1.143 -0.5588)
			(stroke
				(width 0)
				(type default)
			)
			(fill no)
			(layer "F.CrtYd")
		)
		(fp_line
			(start 0.508 0.3048)
			(end 0.508 -0.3048)
			(stroke
				(width 0.1)
				(type default)
			)
			(layer "F.Fab")
		)
		(fp_line
			(start 0.508 -0.3048)
			(end -0.508 -0.3048)
			(stroke
				(width 0.1)
				(type default)
			)
			(layer "F.Fab")
		)
		(fp_line
			(start -0.508 0.3048)
			(end 0.508 0.3048)
			(stroke
				(width 0.1)
				(type default)
			)
			(layer "F.Fab")
		)
		(fp_line
			(start -0.508 -0.3048)
			(end -0.508 0.3048)
			(stroke
				(width 0.1)
				(type default)
			)
			(layer "F.Fab")
		)
		(pad "1" smd rect
			(at -0.5334 0 180)
			(size 0.7112 0.6096)
			(layers "F.Cu" "F.Mask" "F.Paste")
			(net "XP3R3V_FPGA")
		)
		(pad "2" smd rect
			(at 0.5334 0 180)
			(size 0.7112 0.6096)
			(layers "F.Cu" "F.Mask" "F.Paste")
			(net "CFGBVS")
		)
		(zone
			(layer "F.Cu")
			(hatch none 0.5)
			(connect_pads
				(clearance 0)
			)
			(min_thickness 0.25)
			(keepout
				(tracks allowed)
				(vias not_allowed)
				(pads allowed)
				(copperpour not_allowed)
				(footprints allowed)
			)
			(placement
				(enabled no)
				(sheetname "")
			)
			(fill
				(thermal_gap 0.5)
				(thermal_bridge_width 0.5)
				(island_removal_mode 0)
			)
			(polygon
				(pts
					(xy 126.4158 -34.2138) (xy 126.4158 -33.6042) (xy 126.5682 -33.6042) (xy 126.5682 -34.2138)
				)
			)
		)
	)
)
